FILE_TYPE = CONNECTIVITY;
{Allegro Design Entry HDL 17.2-2016 S081 (4005846) 1/11/2022}
"PAGE_NUMBER" = 12;
0"NC";
1"M_C_CPU0_SA_DQ<31:0>";
2"M_C_CPU0_SB_DQ<31:0>";
3"M_C_CPU0_SA_CB<7:0>";
4"M_C_CPU0_SB_CB<7:0>";
5"M_C_CPU0_SA_DQS_DP<9:0>";
6"M_C_CPU0_SB_DQS_DP<9:0>";
7"M_C_CPU0_SA_CA<6:0>";
8"M_C_CPU0_SB_CA<6:0>";
9"M_C_CPU0_SA_DQS_DN<9:0>";
10"M_C_CPU0_SB_DQS_DN<9:0>";
11"M_C_CPU0_ALERT_N";
12"TP_M_C_CPU0_SA_TEST39C";
13"M_C_CPU0_ALERT_R_N";
14"M_C_CPU0_CLK_DP<0>";
15"M_C_CPU0_CLK_DN<0>";
16"M_C_CPU0_SA_RSP<0>";
17"M_C_CPU0_SA_CS_N<0>";
18"M_C_CPU0_SA_CS_N<1>";
19"M_C_CPU0_SA_PAR";
20"M_C_CPU0_SB_CS_N<0>";
21"M_C_CPU0_SB_CS_N<1>";
22"M_C_CPU0_SB_RSP<0>";
23"M_C_CPU0_SB_PAR";
24"M_C_CPU0_RESET_N";
25"M_C_CPU0_SB_DQS_DP<9>";
26"M_C_CPU0_SB_CA<6>";
27"M_C_CPU0_SB_DQS_DN<9>";
28"M_C_CPU0_SA_CA<6>";
29"M_C_CPU0_SB_CA<5>";
30"M_C_CPU0_SB_DQS_DN<8>";
31"M_C_CPU0_SA_CA<5>";
32"M_C_CPU0_SB_CA<4>";
33"M_C_CPU0_SA_CA<4>";
34"M_C_CPU0_SB_CA<3>";
35"M_C_CPU0_SA_CA<3>";
36"M_C_CPU0_SB_CA<2>";
37"M_C_CPU0_SA_CA<2>";
38"M_C_CPU0_SB_CA<1>";
39"M_C_CPU0_SA_CA<1>";
40"M_C_CPU0_SB_CA<0>";
41"M_C_CPU0_SA_CA<0>";
42"M_C_CPU0_SB_DQS_DP<7>";
43"M_C_CPU0_SB_DQS_DP<6>";
44"M_C_CPU0_SB_DQS_DP<5>";
45"M_C_CPU0_SB_DQS_DP<4>";
46"M_C_CPU0_SA_DQS_DP<9>";
47"M_C_CPU0_SB_DQS_DP<3>";
48"M_C_CPU0_SB_DQS_DN<7>";
49"M_C_CPU0_SB_DQS_DP<2>";
50"M_C_CPU0_SB_DQS_DN<6>";
51"M_C_CPU0_SB_DQS_DP<1>";
52"M_C_CPU0_SB_DQS_DN<5>";
53"M_C_CPU0_SB_DQS_DP<0>";
54"M_C_CPU0_SB_DQS_DN<4>";
55"M_C_CPU0_SA_DQS_DN<9>";
56"M_C_CPU0_SB_DQS_DN<3>";
57"M_C_CPU0_SA_DQS_DN<8>";
58"M_C_CPU0_SB_DQS_DN<2>";
59"M_C_CPU0_SB_DQS_DN<1>";
60"M_C_CPU0_SB_DQS_DN<0>";
61"M_C_CPU0_SB_DQS_DP<8>";
62"M_C_CPU0_SA_DQS_DN<0>";
63"M_C_CPU0_SA_DQS_DP<8>";
64"M_C_CPU0_SA_DQS_DP<7>";
65"M_C_CPU0_SA_DQS_DP<6>";
66"M_C_CPU0_SA_DQS_DP<5>";
67"M_C_CPU0_SA_DQS_DP<4>";
68"M_C_CPU0_SA_DQS_DP<3>";
69"M_C_CPU0_SA_DQS_DN<7>";
70"M_C_CPU0_SA_DQS_DP<2>";
71"M_C_CPU0_SA_DQS_DN<6>";
72"M_C_CPU0_SA_DQS_DP<1>";
73"M_C_CPU0_SA_DQS_DN<5>";
74"M_C_CPU0_SA_DQS_DP<0>";
75"M_C_CPU0_SA_DQS_DN<4>";
76"M_C_CPU0_SA_DQS_DN<3>";
77"M_C_CPU0_SA_DQS_DN<2>";
78"M_C_CPU0_SA_DQS_DN<1>";
79"M_C_CPU0_SB_CB<7>";
80"M_C_CPU0_SB_CB<6>";
81"M_C_CPU0_SB_CB<5>";
82"M_C_CPU0_SB_CB<4>";
83"M_C_CPU0_SB_CB<3>";
84"M_C_CPU0_SB_CB<2>";
85"M_C_CPU0_SA_CB<7>";
86"M_C_CPU0_SB_CB<1>";
87"M_C_CPU0_SB_CB<0>";
88"M_C_CPU0_SA_CB<4>";
89"M_C_CPU0_SA_CB<3>";
90"M_C_CPU0_SA_CB<2>";
91"M_C_CPU0_SA_CB<1>";
92"M_C_CPU0_SA_CB<0>";
93"M_C_CPU0_SB_DQ<29>";
94"M_C_CPU0_SB_DQ<28>";
95"M_C_CPU0_SB_DQ<27>";
96"M_C_CPU0_SB_DQ<26>";
97"M_C_CPU0_SB_DQ<25>";
98"M_C_CPU0_SB_DQ<24>";
99"M_C_CPU0_SB_DQ<23>";
100"M_C_CPU0_SB_DQ<22>";
101"M_C_CPU0_SB_DQ<21>";
102"M_C_CPU0_SA_CB<6>";
103"M_C_CPU0_SB_DQ<20>";
104"M_C_CPU0_SB_DQ<31>";
105"M_C_CPU0_SA_CB<5>";
106"M_C_CPU0_SB_DQ<30>";
107"M_C_CPU0_SB_DQ<7>";
108"M_C_CPU0_SB_DQ<6>";
109"M_C_CPU0_SB_DQ<5>";
110"M_C_CPU0_SB_DQ<4>";
111"M_C_CPU0_SB_DQ<3>";
112"M_C_CPU0_SB_DQ<2>";
113"M_C_CPU0_SB_DQ<19>";
114"M_C_CPU0_SB_DQ<18>";
115"M_C_CPU0_SB_DQ<17>";
116"M_C_CPU0_SB_DQ<16>";
117"M_C_CPU0_SB_DQ<15>";
118"M_C_CPU0_SB_DQ<14>";
119"M_C_CPU0_SB_DQ<13>";
120"M_C_CPU0_SB_DQ<12>";
121"M_C_CPU0_SB_DQ<11>";
122"M_C_CPU0_SB_DQ<10>";
123"M_C_CPU0_SB_DQ<9>";
124"M_C_CPU0_SB_DQ<8>";
125"M_C_CPU0_SA_DQ<24>";
126"M_C_CPU0_SA_DQ<23>";
127"M_C_CPU0_SA_DQ<22>";
128"M_C_CPU0_SA_DQ<21>";
129"M_C_CPU0_SA_DQ<20>";
130"M_C_CPU0_SA_DQ<31>";
131"M_C_CPU0_SA_DQ<30>";
132"M_C_CPU0_SB_DQ<1>";
133"M_C_CPU0_SB_DQ<0>";
134"M_C_CPU0_SA_DQ<19>";
135"M_C_CPU0_SA_DQ<18>";
136"M_C_CPU0_SA_DQ<29>";
137"M_C_CPU0_SA_DQ<17>";
138"M_C_CPU0_SA_DQ<28>";
139"M_C_CPU0_SA_DQ<16>";
140"M_C_CPU0_SA_DQ<27>";
141"M_C_CPU0_SA_DQ<26>";
142"M_C_CPU0_SA_DQ<25>";
143"M_C_CPU0_SA_DQ<8>";
144"M_C_CPU0_SA_DQ<13>";
145"M_C_CPU0_SA_DQ<7>";
146"M_C_CPU0_SA_DQ<12>";
147"M_C_CPU0_SA_DQ<6>";
148"M_C_CPU0_SA_DQ<11>";
149"M_C_CPU0_SA_DQ<5>";
150"M_C_CPU0_SA_DQ<10>";
151"M_C_CPU0_SA_DQ<4>";
152"M_C_CPU0_SA_DQ<3>";
153"M_C_CPU0_SA_DQ<2>";
154"M_C_CPU0_SA_DQ<1>";
155"M_C_CPU0_SA_DQ<0>";
156"M_C_CPU0_SA_DQ<15>";
157"M_C_CPU0_SA_DQ<9>";
158"M_C_CPU0_SA_DQ<14>";
%"GENOA_SP5"
"3","(-4775,3575)","0","pure_quanta","I159";
;
LOCATION"U25"
$SEC"3"
CDS_SEC"3"
PART_TYPE"SMLF"
MATERIAL"IO"
VALUE"SOCKET6096_13568-001"
PART_NUMBER"DGA^6000030"
CDS_LIB"pure_quanta"
CDS_LMAN_SYM_OUTLINE"-650,2525,650,-2525"
NEEDS_NO_SIZE"TRUE";
"TEST39C"
$PN"BF55"12;
"MC1_CLK_L"
$PN"BG57"0;
"MC1_CLK_H"
$PN"BF56"0;
"MC0_CLK_L"
$PN"BD56"15;
"MC0_CLK_H"
$PN"BC57"14;
"MCB_PAR"
$PN"BL57"23;
"MCA_PAR"
$PN"BC55"19;
"MCB_DQS_H9"
$PN"BV56"25;
"MCA_CHECK4"
$PN"AN57"88;
"MCA_DATA8"
$PN"L57"143;
"MCA_DATA13"
$PN"T55"144;
"MCA_DATA24"
$PN"AC57"125;
"MCA_DQS_L0"
$PN"H56"62;
"MCB0_CS_L0"
$PN"BM55"20;
"MCB1_CS_L0"
$PN"BL55"0;
"MCB_DATA7"
$PN"CH55"107;
"MCB_DQS_H7"
$PN"CV55"42;
"MCA_CHECK3"
$PN"AL55"89;
"MCA_DATA7"
$PN"L55"145;
"MCA_DATA12"
$PN"R57"146;
"MCA_DATA23"
$PN"AC55"126;
"MCB_DATA6"
$PN"CG57"108;
"MCB_DQS_H6"
$PN"CM55"43;
"MCA_CHECK2"
$PN"AK56"90;
"MCA_DATA6"
$PN"K56"147;
"MCA_DATA11"
$PN"N55"148;
"MCA_DATA22"
$PN"AB56"127;
"MCB_CA6"
$PN"BK56"26;
"MCB_DATA5"
$PN"CG55"109;
"MCB_DQS_H5"
$PN"CF55"44;
"MCB_DQS_L9"
$PN"BW57"27;
"MCA_CA6"
$PN"BB55"28;
"MCA_CHECK1"
$PN"AK55"91;
"MCA_DATA5"
$PN"K55"149;
"MCA_DATA10"
$PN"M56"150;
"MCA_DATA21"
$PN"AB55"128;
"MCB_CA5"
$PN"BK55"29;
"MCB_DATA4"
$PN"CF56"110;
"MCB_DQS_H4"
$PN"BY55"45;
"MCB_DQS_L8"
$PN"DC55"30;
"MCA_CA5"
$PN"BB56"31;
"MCA_CHECK0"
$PN"AJ57"92;
"MCA_DATA4"
$PN"J57"151;
"MCA_DATA20"
$PN"AA57"129;
"MCA_DATA31"
$PN"AJ55"130;
"MCA_DQS_H9"
$PN"AN55"46;
"MCB_CA4"
$PN"BJ55"32;
"MCB_DATA3"
$PN"CD55"111;
"MCB_DQS_H3"
$PN"DB56"47;
"MCB_DQS_L7"
$PN"CU55"48;
"MCA1_CS_L1"
$PN"AV55"0;
"MCA_CA4"
$PN"BA57"33;
"MCA_DATA3"
$PN"G55"152;
"MCA_DATA30"
$PN"AH56"131;
"MCA_DQS_H8"
$PN"AG55"63;
"MCB_CA3"
$PN"BJ57"34;
"MCB_DATA2"
$PN"CC57"112;
"MCB_DATA19"
$PN"CT55"113;
"MCB_DQS_H2"
$PN"CT56"49;
"MCB_DQS_L6"
$PN"CL55"50;
"MCA0_CS_L1"
$PN"AW55"18;
"MCA1_CS_L0"
$PN"AU57"0;
"MCA_CA3"
$PN"BA55"35;
"MCA_DATA2"
$PN"F56"153;
"MCA_DQS_H7"
$PN"AA55"64;
"MCB_CA2"
$PN"BH56"36;
"MCB_DATA1"
$PN"CC55"132;
"MCB_DATA18"
$PN"CR57"114;
"MCB_DATA29"
$PN"DE55"93;
"MCB_DQS_H1"
$PN"CK56"51;
"MCB_DQS_L5"
$PN"CE55"52;
"MCA0_CS_L0"
$PN"AV56"17;
"MCA_CA2"
$PN"AY55"37;
"MCA_DATA1"
$PN"F55"154;
"MCA_DQS_H6"
$PN"R55"65;
"MCB_CA1"
$PN"BH55"38;
"MCB_DATA0"
$PN"CB56"133;
"MCB_DATA17"
$PN"CR55"115;
"MCB_DATA28"
$PN"DD56"94;
"MCB_DQS_H0"
$PN"CD56"53;
"MCB_DQS_L4"
$PN"BW55"54;
"MCA_CA1"
$PN"AY56"39;
"MCA_DATA0"
$PN"E57"155;
"MCA_DQS_H5"
$PN"J55"66;
"MCA_DQS_L9"
$PN"AM55"55;
"MCB0_RSP_L"
$PN"BP56"22;
"MCB1_RSP_L"
$PN"BR57"0;
"MCB_CA0"
$PN"BG55"40;
"MCB_CHECK7"
$PN"BV55"79;
"MCB_DATA16"
$PN"CP56"116;
"MCB_DATA27"
$PN"DB55"95;
"MCB_DQS_L3"
$PN"DC57"56;
"MCA_CA0"
$PN"AW57"41;
"MCA_DQS_H4"
$PN"AL57"67;
"MCA_DQS_L8"
$PN"AF55"57;
"MCB_CHECK6"
$PN"BU57"80;
"MCB_DATA15"
$PN"CP55"117;
"MCB_DATA26"
$PN"DA57"96;
"MCB_DQS_L2"
$PN"CU57"58;
"MCA_DQS_H3"
$PN"AE57"68;
"MCA_DQS_L7"
$PN"Y55"69;
"MCB_CHECK5"
$PN"BU55"81;
"MCB_DATA14"
$PN"CN57"118;
"MCB_DATA25"
$PN"DA55"97;
"MCB_DQS_L1"
$PN"CL57"59;
"MCA_DATA19"
$PN"W55"134;
"MCA_DQS_H2"
$PN"W57"70;
"MCA_DQS_L6"
$PN"P55"71;
"MCB_CHECK4"
$PN"BT56"82;
"MCB_DATA13"
$PN"CN55"119;
"MCB_DATA24"
$PN"CY56"98;
"MCB_DQS_L0"
$PN"CE57"60;
"MCA_DATA18"
$PN"V56"135;
"MCA_DATA29"
$PN"AH55"136;
"MCA_DQS_H1"
$PN"N57"72;
"MCA_DQS_L5"
$PN"H55"73;
"MCB_CHECK3"
$PN"CB55"83;
"MCB_DATA12"
$PN"CM56"120;
"MCB_DATA23"
$PN"CY55"99;
"MCA_DATA17"
$PN"V55"137;
"MCA_DATA28"
$PN"AG57"138;
"MCA_DQS_H0"
$PN"G57"74;
"MCA_DQS_L4"
$PN"AM56"75;
"MCB_CHECK2"
$PN"CA57"84;
"MCB_DATA11"
$PN"CK55"121;
"MCB_DATA22"
$PN"CW57"100;
"MCA1_RSP_L"
$PN"BP55"0;
"MCA_CHECK7"
$PN"AR55"85;
"MCA_DATA16"
$PN"U57"139;
"MCA_DATA27"
$PN"AE55"140;
"MCA_DQS_L3"
$PN"AF56"76;
"MCB_CHECK1"
$PN"CA55"86;
"MCB_DATA10"
$PN"CJ57"122;
"MCB_DATA21"
$PN"CW55"101;
"MCA0_RSP_L"
$PN"BN55"16;
"MCA_CHECK6"
$PN"AP56"102;
"MCA_DATA15"
$PN"U55"156;
"MCA_DATA26"
$PN"AD56"141;
"MCA_DQS_L2"
$PN"Y56"77;
"MCB_CHECK0"
$PN"BY56"87;
"MCB_DATA9"
$PN"CJ55"123;
"MCB_DATA20"
$PN"CV56"103;
"MCB_DATA31"
$PN"DF55"104;
"MCA_CHECK5"
$PN"AP55"105;
"MCA_DATA9"
$PN"M55"157;
"MCA_DATA14"
$PN"T56"158;
"MCA_DATA25"
$PN"AD55"142;
"MCA_DQS_L1"
$PN"P56"78;
"MCB0_CS_L1"
$PN"BN57"21;
"MCB1_CS_L1"
$PN"BM56"0;
"MCB_DATA8"
$PN"CH56"124;
"MCB_DATA30"
$PN"DE57"106;
"MCB_DQS_H8"
$PN"DD55"61;
"MC_RESET_L"
$PN"AU55"24;
"MC_ALERT_L"
$PN"AT55"13;
%"TAP"
"1","(-3500,5900)","0","mstr_standard","I162";
;
CDS_LIB"mstr_standard"
BODY_TYPE"PLUMBING"
HDL_TAP"TRUE";
"B \NAC \NWC"1;
"S \NAC"
BN"1"154;
%"TAP"
"1","(-3500,5950)","0","mstr_standard","I163";
;
CDS_LIB"mstr_standard"
BODY_TYPE"PLUMBING"
HDL_TAP"TRUE";
"B \NAC \NWC"1;
"S \NAC"
BN"0"155;
%"TAP"
"1","(-3500,5850)","0","mstr_standard","I164";
;
CDS_LIB"mstr_standard"
BODY_TYPE"PLUMBING"
HDL_TAP"TRUE";
"B \NAC \NWC"1;
"S \NAC"
BN"2"153;
%"TAP"
"1","(-3500,5800)","0","mstr_standard","I165";
;
CDS_LIB"mstr_standard"
BODY_TYPE"PLUMBING"
HDL_TAP"TRUE";
"B \NAC \NWC"1;
"S \NAC"
BN"3"152;
%"TAP"
"1","(-3500,5750)","0","mstr_standard","I166";
;
CDS_LIB"mstr_standard"
BODY_TYPE"PLUMBING"
HDL_TAP"TRUE";
"B \NAC \NWC"1;
"S \NAC"
BN"4"151;
%"TAP"
"1","(-3500,5700)","0","mstr_standard","I167";
;
CDS_LIB"mstr_standard"
BODY_TYPE"PLUMBING"
HDL_TAP"TRUE";
"B \NAC \NWC"1;
"S \NAC"
BN"5"149;
%"TAP"
"1","(-3500,5650)","0","mstr_standard","I168";
;
CDS_LIB"mstr_standard"
BODY_TYPE"PLUMBING"
HDL_TAP"TRUE";
"B \NAC \NWC"1;
"S \NAC"
BN"6"147;
%"TAP"
"1","(-3500,5600)","0","mstr_standard","I169";
;
CDS_LIB"mstr_standard"
BODY_TYPE"PLUMBING"
HDL_TAP"TRUE";
"B \NAC \NWC"1;
"S \NAC"
BN"7"145;
%"TAP"
"1","(-3500,5500)","0","mstr_standard","I170";
;
CDS_LIB"mstr_standard"
BODY_TYPE"PLUMBING"
HDL_TAP"TRUE";
"B \NAC \NWC"1;
"S \NAC"
BN"8"143;
%"TAP"
"1","(-3500,5400)","0","mstr_standard","I171";
;
CDS_LIB"mstr_standard"
BODY_TYPE"PLUMBING"
HDL_TAP"TRUE";
"B \NAC \NWC"1;
"S \NAC"
BN"10"150;
%"TAP"
"1","(-3500,5450)","0","mstr_standard","I172";
;
CDS_LIB"mstr_standard"
BODY_TYPE"PLUMBING"
HDL_TAP"TRUE";
"B \NAC \NWC"1;
"S \NAC"
BN"9"157;
%"TAP"
"1","(-3500,5350)","0","mstr_standard","I173";
;
CDS_LIB"mstr_standard"
BODY_TYPE"PLUMBING"
HDL_TAP"TRUE";
"B \NAC \NWC"1;
"S \NAC"
BN"11"148;
%"TAP"
"1","(-3500,5300)","0","mstr_standard","I174";
;
CDS_LIB"mstr_standard"
BODY_TYPE"PLUMBING"
HDL_TAP"TRUE";
"B \NAC \NWC"1;
"S \NAC"
BN"12"146;
%"TAP"
"1","(-3500,5250)","0","mstr_standard","I175";
;
CDS_LIB"mstr_standard"
BODY_TYPE"PLUMBING"
HDL_TAP"TRUE";
"B \NAC \NWC"1;
"S \NAC"
BN"13"144;
%"TAP"
"1","(-3500,5200)","0","mstr_standard","I176";
;
CDS_LIB"mstr_standard"
BODY_TYPE"PLUMBING"
HDL_TAP"TRUE";
"B \NAC \NWC"1;
"S \NAC"
BN"14"158;
%"TAP"
"1","(-3500,5150)","0","mstr_standard","I177";
;
CDS_LIB"mstr_standard"
BODY_TYPE"PLUMBING"
HDL_TAP"TRUE";
"B \NAC \NWC"1;
"S \NAC"
BN"15"156;
%"TAP"
"1","(-3500,5050)","0","mstr_standard","I178";
;
CDS_LIB"mstr_standard"
BODY_TYPE"PLUMBING"
HDL_TAP"TRUE";
"B \NAC \NWC"1;
"S \NAC"
BN"16"139;
%"TAP"
"1","(-3500,5000)","0","mstr_standard","I179";
;
CDS_LIB"mstr_standard"
BODY_TYPE"PLUMBING"
HDL_TAP"TRUE";
"B \NAC \NWC"1;
"S \NAC"
BN"17"137;
%"TAP"
"1","(-3500,4950)","0","mstr_standard","I180";
;
CDS_LIB"mstr_standard"
BODY_TYPE"PLUMBING"
HDL_TAP"TRUE";
"B \NAC \NWC"1;
"S \NAC"
BN"18"135;
%"TAP"
"1","(-3500,4900)","0","mstr_standard","I181";
;
CDS_LIB"mstr_standard"
BODY_TYPE"PLUMBING"
HDL_TAP"TRUE";
"B \NAC \NWC"1;
"S \NAC"
BN"19"134;
%"TAP"
"1","(-3500,4850)","0","mstr_standard","I182";
;
CDS_LIB"mstr_standard"
BODY_TYPE"PLUMBING"
HDL_TAP"TRUE";
"B \NAC \NWC"1;
"S \NAC"
BN"20"129;
%"TAP"
"1","(-3500,4800)","0","mstr_standard","I183";
;
CDS_LIB"mstr_standard"
BODY_TYPE"PLUMBING"
HDL_TAP"TRUE";
"B \NAC \NWC"1;
"S \NAC"
BN"21"128;
%"TAP"
"1","(-3500,4750)","0","mstr_standard","I184";
;
CDS_LIB"mstr_standard"
BODY_TYPE"PLUMBING"
HDL_TAP"TRUE";
"B \NAC \NWC"1;
"S \NAC"
BN"22"127;
%"TAP"
"1","(-3500,4700)","0","mstr_standard","I185";
;
CDS_LIB"mstr_standard"
BODY_TYPE"PLUMBING"
HDL_TAP"TRUE";
"B \NAC \NWC"1;
"S \NAC"
BN"23"126;
%"TAP"
"1","(-3500,4600)","0","mstr_standard","I186";
;
CDS_LIB"mstr_standard"
BODY_TYPE"PLUMBING"
HDL_TAP"TRUE";
"B \NAC \NWC"1;
"S \NAC"
BN"24"125;
%"TAP"
"1","(-3500,4550)","0","mstr_standard","I187";
;
CDS_LIB"mstr_standard"
BODY_TYPE"PLUMBING"
HDL_TAP"TRUE";
"B \NAC \NWC"1;
"S \NAC"
BN"25"142;
%"TAP"
"1","(-3500,4500)","0","mstr_standard","I188";
;
CDS_LIB"mstr_standard"
BODY_TYPE"PLUMBING"
HDL_TAP"TRUE";
"B \NAC \NWC"1;
"S \NAC"
BN"26"141;
%"TAP"
"1","(-3500,4450)","0","mstr_standard","I189";
;
CDS_LIB"mstr_standard"
BODY_TYPE"PLUMBING"
HDL_TAP"TRUE";
"B \NAC \NWC"1;
"S \NAC"
BN"27"140;
%"TAP"
"1","(-3500,4400)","0","mstr_standard","I190";
;
CDS_LIB"mstr_standard"
BODY_TYPE"PLUMBING"
HDL_TAP"TRUE";
"B \NAC \NWC"1;
"S \NAC"
BN"28"138;
%"TAP"
"1","(-3500,4350)","0","mstr_standard","I191";
;
CDS_LIB"mstr_standard"
BODY_TYPE"PLUMBING"
HDL_TAP"TRUE";
"B \NAC \NWC"1;
"S \NAC"
BN"29"136;
%"TAP"
"1","(-3500,4300)","0","mstr_standard","I192";
;
CDS_LIB"mstr_standard"
BODY_TYPE"PLUMBING"
HDL_TAP"TRUE";
"B \NAC \NWC"1;
"S \NAC"
BN"30"131;
%"TAP"
"1","(-3500,4250)","0","mstr_standard","I193";
;
CDS_LIB"mstr_standard"
BODY_TYPE"PLUMBING"
HDL_TAP"TRUE";
"B \NAC \NWC"1;
"S \NAC"
BN"31"130;
%"TAP"
"1","(-3500,4100)","0","mstr_standard","I194";
;
CDS_LIB"mstr_standard"
BODY_TYPE"PLUMBING"
HDL_TAP"TRUE";
"B \NAC \NWC"2;
"S \NAC"
BN"1"132;
%"TAP"
"1","(-3500,4150)","0","mstr_standard","I195";
;
CDS_LIB"mstr_standard"
BODY_TYPE"PLUMBING"
HDL_TAP"TRUE";
"B \NAC \NWC"2;
"S \NAC"
BN"0"133;
%"TAP"
"1","(-3500,4050)","0","mstr_standard","I197";
;
CDS_LIB"mstr_standard"
BODY_TYPE"PLUMBING"
HDL_TAP"TRUE";
"B \NAC \NWC"2;
"S \NAC"
BN"2"112;
%"TAP"
"1","(-3500,4000)","0","mstr_standard","I198";
;
CDS_LIB"mstr_standard"
BODY_TYPE"PLUMBING"
HDL_TAP"TRUE";
"B \NAC \NWC"2;
"S \NAC"
BN"3"111;
%"TAP"
"1","(-3500,3950)","0","mstr_standard","I199";
;
CDS_LIB"mstr_standard"
BODY_TYPE"PLUMBING"
HDL_TAP"TRUE";
"B \NAC \NWC"2;
"S \NAC"
BN"4"110;
%"TAP"
"1","(-3500,3900)","0","mstr_standard","I200";
;
CDS_LIB"mstr_standard"
BODY_TYPE"PLUMBING"
HDL_TAP"TRUE";
"B \NAC \NWC"2;
"S \NAC"
BN"5"109;
%"TAP"
"1","(-3500,3850)","0","mstr_standard","I201";
;
CDS_LIB"mstr_standard"
BODY_TYPE"PLUMBING"
HDL_TAP"TRUE";
"B \NAC \NWC"2;
"S \NAC"
BN"6"108;
%"TAP"
"1","(-3500,3800)","0","mstr_standard","I202";
;
CDS_LIB"mstr_standard"
BODY_TYPE"PLUMBING"
HDL_TAP"TRUE";
"B \NAC \NWC"2;
"S \NAC"
BN"7"107;
%"TAP"
"1","(-3500,3700)","0","mstr_standard","I203";
;
CDS_LIB"mstr_standard"
BODY_TYPE"PLUMBING"
HDL_TAP"TRUE";
"B \NAC \NWC"2;
"S \NAC"
BN"8"124;
%"TAP"
"1","(-3500,3650)","0","mstr_standard","I204";
;
CDS_LIB"mstr_standard"
BODY_TYPE"PLUMBING"
HDL_TAP"TRUE";
"B \NAC \NWC"2;
"S \NAC"
BN"9"123;
%"TAP"
"1","(-3500,3600)","0","mstr_standard","I205";
;
CDS_LIB"mstr_standard"
BODY_TYPE"PLUMBING"
HDL_TAP"TRUE";
"B \NAC \NWC"2;
"S \NAC"
BN"10"122;
%"TAP"
"1","(-3500,3550)","0","mstr_standard","I206";
;
CDS_LIB"mstr_standard"
BODY_TYPE"PLUMBING"
HDL_TAP"TRUE";
"B \NAC \NWC"2;
"S \NAC"
BN"11"121;
%"TAP"
"1","(-3500,3500)","0","mstr_standard","I207";
;
CDS_LIB"mstr_standard"
BODY_TYPE"PLUMBING"
HDL_TAP"TRUE";
"B \NAC \NWC"2;
"S \NAC"
BN"12"120;
%"TAP"
"1","(-3500,3400)","0","mstr_standard","I208";
;
CDS_LIB"mstr_standard"
BODY_TYPE"PLUMBING"
HDL_TAP"TRUE";
"B \NAC \NWC"2;
"S \NAC"
BN"14"118;
%"TAP"
"1","(-3500,3350)","0","mstr_standard","I209";
;
CDS_LIB"mstr_standard"
BODY_TYPE"PLUMBING"
HDL_TAP"TRUE";
"B \NAC \NWC"2;
"S \NAC"
BN"15"117;
%"TAP"
"1","(-3500,3450)","0","mstr_standard","I210";
;
CDS_LIB"mstr_standard"
BODY_TYPE"PLUMBING"
HDL_TAP"TRUE";
"B \NAC \NWC"2;
"S \NAC"
BN"13"119;
%"TAP"
"1","(-3500,3250)","0","mstr_standard","I211";
;
CDS_LIB"mstr_standard"
BODY_TYPE"PLUMBING"
HDL_TAP"TRUE";
"B \NAC \NWC"2;
"S \NAC"
BN"16"116;
%"TAP"
"1","(-3500,3200)","0","mstr_standard","I212";
;
CDS_LIB"mstr_standard"
BODY_TYPE"PLUMBING"
HDL_TAP"TRUE";
"B \NAC \NWC"2;
"S \NAC"
BN"17"115;
%"TAP"
"1","(-3500,3150)","0","mstr_standard","I213";
;
CDS_LIB"mstr_standard"
BODY_TYPE"PLUMBING"
HDL_TAP"TRUE";
"B \NAC \NWC"2;
"S \NAC"
BN"18"114;
%"TAP"
"1","(-3500,3100)","0","mstr_standard","I214";
;
CDS_LIB"mstr_standard"
BODY_TYPE"PLUMBING"
HDL_TAP"TRUE";
"B \NAC \NWC"2;
"S \NAC"
BN"19"113;
%"TAP"
"1","(-3500,2950)","0","mstr_standard","I215";
;
CDS_LIB"mstr_standard"
BODY_TYPE"PLUMBING"
HDL_TAP"TRUE";
"B \NAC \NWC"2;
"S \NAC"
BN"22"100;
%"TAP"
"1","(-3500,3050)","0","mstr_standard","I216";
;
CDS_LIB"mstr_standard"
BODY_TYPE"PLUMBING"
HDL_TAP"TRUE";
"B \NAC \NWC"2;
"S \NAC"
BN"20"103;
%"TAP"
"1","(-3500,2900)","0","mstr_standard","I217";
;
CDS_LIB"mstr_standard"
BODY_TYPE"PLUMBING"
HDL_TAP"TRUE";
"B \NAC \NWC"2;
"S \NAC"
BN"23"99;
%"TAP"
"1","(-3500,3000)","0","mstr_standard","I218";
;
CDS_LIB"mstr_standard"
BODY_TYPE"PLUMBING"
HDL_TAP"TRUE";
"B \NAC \NWC"2;
"S \NAC"
BN"21"101;
%"TAP"
"1","(-3500,2800)","0","mstr_standard","I219";
;
CDS_LIB"mstr_standard"
BODY_TYPE"PLUMBING"
HDL_TAP"TRUE";
"B \NAC \NWC"2;
"S \NAC"
BN"24"98;
%"TAP"
"1","(-3500,2700)","0","mstr_standard","I220";
;
CDS_LIB"mstr_standard"
BODY_TYPE"PLUMBING"
HDL_TAP"TRUE";
"B \NAC \NWC"2;
"S \NAC"
BN"26"96;
%"TAP"
"1","(-3500,2750)","0","mstr_standard","I221";
;
CDS_LIB"mstr_standard"
BODY_TYPE"PLUMBING"
HDL_TAP"TRUE";
"B \NAC \NWC"2;
"S \NAC"
BN"25"97;
%"TAP"
"1","(-3500,2650)","0","mstr_standard","I222";
;
CDS_LIB"mstr_standard"
BODY_TYPE"PLUMBING"
HDL_TAP"TRUE";
"B \NAC \NWC"2;
"S \NAC"
BN"27"95;
%"TAP"
"1","(-3500,2600)","0","mstr_standard","I223";
;
CDS_LIB"mstr_standard"
BODY_TYPE"PLUMBING"
HDL_TAP"TRUE";
"B \NAC \NWC"2;
"S \NAC"
BN"28"94;
%"TAP"
"1","(-3500,2550)","0","mstr_standard","I224";
;
CDS_LIB"mstr_standard"
BODY_TYPE"PLUMBING"
HDL_TAP"TRUE";
"B \NAC \NWC"2;
"S \NAC"
BN"29"93;
%"TAP"
"1","(-3500,2500)","0","mstr_standard","I225";
;
CDS_LIB"mstr_standard"
BODY_TYPE"PLUMBING"
HDL_TAP"TRUE";
"B \NAC \NWC"2;
"S \NAC"
BN"30"106;
%"TAP"
"1","(-3500,2450)","0","mstr_standard","I226";
;
CDS_LIB"mstr_standard"
BODY_TYPE"PLUMBING"
HDL_TAP"TRUE";
"B \NAC \NWC"2;
"S \NAC"
BN"31"104;
%"TAP"
"1","(-3500,2350)","0","mstr_standard","I227";
;
CDS_LIB"mstr_standard"
BODY_TYPE"PLUMBING"
HDL_TAP"TRUE";
"B \NAC \NWC"3;
"S \NAC"
BN"0"92;
%"TAP"
"1","(-3500,2300)","0","mstr_standard","I228";
;
CDS_LIB"mstr_standard"
BODY_TYPE"PLUMBING"
HDL_TAP"TRUE";
"B \NAC \NWC"3;
"S \NAC"
BN"1"91;
%"TAP"
"1","(-3500,2250)","0","mstr_standard","I229";
;
CDS_LIB"mstr_standard"
BODY_TYPE"PLUMBING"
HDL_TAP"TRUE";
"B \NAC \NWC"3;
"S \NAC"
BN"2"90;
%"TAP"
"1","(-3500,2200)","0","mstr_standard","I230";
;
CDS_LIB"mstr_standard"
BODY_TYPE"PLUMBING"
HDL_TAP"TRUE";
"B \NAC \NWC"3;
"S \NAC"
BN"3"89;
%"TAP"
"1","(-3500,2150)","0","mstr_standard","I231";
;
CDS_LIB"mstr_standard"
BODY_TYPE"PLUMBING"
HDL_TAP"TRUE";
"B \NAC \NWC"3;
"S \NAC"
BN"4"88;
%"TAP"
"1","(-3500,2100)","0","mstr_standard","I232";
;
CDS_LIB"mstr_standard"
BODY_TYPE"PLUMBING"
HDL_TAP"TRUE";
"B \NAC \NWC"3;
"S \NAC"
BN"5"105;
%"TAP"
"1","(-3500,2050)","0","mstr_standard","I233";
;
CDS_LIB"mstr_standard"
BODY_TYPE"PLUMBING"
HDL_TAP"TRUE";
"B \NAC \NWC"3;
"S \NAC"
BN"6"102;
%"TAP"
"1","(-3500,2000)","0","mstr_standard","I235";
;
CDS_LIB"mstr_standard"
BODY_TYPE"PLUMBING"
HDL_TAP"TRUE";
"B \NAC \NWC"3;
"S \NAC"
BN"7"85;
%"TAP"
"1","(-3500,1900)","0","mstr_standard","I236";
;
CDS_LIB"mstr_standard"
BODY_TYPE"PLUMBING"
HDL_TAP"TRUE";
"B \NAC \NWC"4;
"S \NAC"
BN"0"87;
%"TAP"
"1","(-3500,1850)","0","mstr_standard","I237";
;
CDS_LIB"mstr_standard"
BODY_TYPE"PLUMBING"
HDL_TAP"TRUE";
"B \NAC \NWC"4;
"S \NAC"
BN"1"86;
%"TAP"
"1","(-3500,1800)","0","mstr_standard","I238";
;
CDS_LIB"mstr_standard"
BODY_TYPE"PLUMBING"
HDL_TAP"TRUE";
"B \NAC \NWC"4;
"S \NAC"
BN"2"84;
%"TAP"
"1","(-3500,1750)","0","mstr_standard","I239";
;
CDS_LIB"mstr_standard"
BODY_TYPE"PLUMBING"
HDL_TAP"TRUE";
"B \NAC \NWC"4;
"S \NAC"
BN"3"83;
%"TAP"
"1","(-3500,1700)","0","mstr_standard","I240";
;
CDS_LIB"mstr_standard"
BODY_TYPE"PLUMBING"
HDL_TAP"TRUE";
"B \NAC \NWC"4;
"S \NAC"
BN"4"82;
%"TAP"
"1","(-3500,1650)","0","mstr_standard","I241";
;
CDS_LIB"mstr_standard"
BODY_TYPE"PLUMBING"
HDL_TAP"TRUE";
"B \NAC \NWC"4;
"S \NAC"
BN"5"81;
%"TAP"
"1","(-3500,1550)","0","mstr_standard","I242";
;
CDS_LIB"mstr_standard"
BODY_TYPE"PLUMBING"
HDL_TAP"TRUE";
"B \NAC \NWC"4;
"S \NAC"
BN"7"79;
%"TAP"
"1","(-3500,1600)","0","mstr_standard","I243";
;
CDS_LIB"mstr_standard"
BODY_TYPE"PLUMBING"
HDL_TAP"TRUE";
"B \NAC \NWC"4;
"S \NAC"
BN"6"80;
%"TAP"
"1","(-5925,5950)","2","mstr_standard","I244";
;
CDS_LIB"mstr_standard"
BODY_TYPE"PLUMBING"
HDL_TAP"TRUE";
"B \NAC \NWC"5;
"S \NAC"
BN"0"74;
%"TAP"
"1","(-5925,5850)","2","mstr_standard","I245";
;
CDS_LIB"mstr_standard"
BODY_TYPE"PLUMBING"
HDL_TAP"TRUE";
"B \NAC \NWC"5;
"S \NAC"
BN"1"72;
%"TAP"
"1","(-5925,5750)","2","mstr_standard","I246";
;
CDS_LIB"mstr_standard"
BODY_TYPE"PLUMBING"
HDL_TAP"TRUE";
"B \NAC \NWC"5;
"S \NAC"
BN"2"70;
%"TAP"
"1","(-5925,5650)","2","mstr_standard","I247";
;
CDS_LIB"mstr_standard"
BODY_TYPE"PLUMBING"
HDL_TAP"TRUE";
"B \NAC \NWC"5;
"S \NAC"
BN"3"68;
%"TAP"
"1","(-5925,5550)","2","mstr_standard","I248";
;
CDS_LIB"mstr_standard"
BODY_TYPE"PLUMBING"
HDL_TAP"TRUE";
"B \NAC \NWC"5;
"S \NAC"
BN"4"67;
%"TAP"
"1","(-5925,5450)","2","mstr_standard","I249";
;
CDS_LIB"mstr_standard"
BODY_TYPE"PLUMBING"
HDL_TAP"TRUE";
"B \NAC \NWC"5;
"S \NAC"
BN"5"66;
%"TAP"
"1","(-5925,5350)","2","mstr_standard","I250";
;
CDS_LIB"mstr_standard"
BODY_TYPE"PLUMBING"
HDL_TAP"TRUE";
"B \NAC \NWC"5;
"S \NAC"
BN"6"65;
%"TAP"
"1","(-5925,5250)","2","mstr_standard","I251";
;
CDS_LIB"mstr_standard"
BODY_TYPE"PLUMBING"
HDL_TAP"TRUE";
"B \NAC \NWC"5;
"S \NAC"
BN"7"64;
%"TAP"
"1","(-5925,5150)","2","mstr_standard","I252";
;
CDS_LIB"mstr_standard"
BODY_TYPE"PLUMBING"
HDL_TAP"TRUE";
"B \NAC \NWC"5;
"S \NAC"
BN"8"63;
%"TAP"
"1","(-5925,5050)","2","mstr_standard","I253";
;
CDS_LIB"mstr_standard"
BODY_TYPE"PLUMBING"
HDL_TAP"TRUE";
"B \NAC \NWC"5;
"S \NAC"
BN"9"46;
%"TAP"
"1","(-5925,4900)","2","mstr_standard","I254";
;
CDS_LIB"mstr_standard"
BODY_TYPE"PLUMBING"
HDL_TAP"TRUE";
"B \NAC \NWC"6;
"S \NAC"
BN"0"53;
%"TAP"
"1","(-5925,4800)","2","mstr_standard","I255";
;
CDS_LIB"mstr_standard"
BODY_TYPE"PLUMBING"
HDL_TAP"TRUE";
"B \NAC \NWC"6;
"S \NAC"
BN"1"51;
%"TAP"
"1","(-5925,4700)","2","mstr_standard","I256";
;
CDS_LIB"mstr_standard"
BODY_TYPE"PLUMBING"
HDL_TAP"TRUE";
"B \NAC \NWC"6;
"S \NAC"
BN"2"49;
%"TAP"
"1","(-5925,4500)","2","mstr_standard","I257";
;
CDS_LIB"mstr_standard"
BODY_TYPE"PLUMBING"
HDL_TAP"TRUE";
"B \NAC \NWC"6;
"S \NAC"
BN"4"45;
%"TAP"
"1","(-5925,4600)","2","mstr_standard","I258";
;
CDS_LIB"mstr_standard"
BODY_TYPE"PLUMBING"
HDL_TAP"TRUE";
"B \NAC \NWC"6;
"S \NAC"
BN"3"47;
%"TAP"
"1","(-5925,4400)","2","mstr_standard","I259";
;
CDS_LIB"mstr_standard"
BODY_TYPE"PLUMBING"
HDL_TAP"TRUE";
"B \NAC \NWC"6;
"S \NAC"
BN"5"44;
%"TAP"
"1","(-5925,4300)","2","mstr_standard","I260";
;
CDS_LIB"mstr_standard"
BODY_TYPE"PLUMBING"
HDL_TAP"TRUE";
"B \NAC \NWC"6;
"S \NAC"
BN"6"43;
%"TAP"
"1","(-5925,4100)","2","mstr_standard","I261";
;
CDS_LIB"mstr_standard"
BODY_TYPE"PLUMBING"
HDL_TAP"TRUE";
"B \NAC \NWC"6;
"S \NAC"
BN"8"61;
%"TAP"
"1","(-5925,4200)","2","mstr_standard","I262";
;
CDS_LIB"mstr_standard"
BODY_TYPE"PLUMBING"
HDL_TAP"TRUE";
"B \NAC \NWC"6;
"S \NAC"
BN"7"42;
%"TAP"
"1","(-6125,5800)","2","mstr_standard","I263";
;
CDS_LIB"mstr_standard"
BODY_TYPE"PLUMBING"
HDL_TAP"TRUE";
"B \NAC \NWC"9;
"S \NAC"
BN"1"78;
%"TAP"
"1","(-6125,5700)","2","mstr_standard","I264";
;
CDS_LIB"mstr_standard"
BODY_TYPE"PLUMBING"
HDL_TAP"TRUE";
"B \NAC \NWC"9;
"S \NAC"
BN"2"77;
%"TAP"
"1","(-6125,5900)","2","mstr_standard","I265";
;
CDS_LIB"mstr_standard"
BODY_TYPE"PLUMBING"
HDL_TAP"TRUE";
"B \NAC \NWC"9;
"S \NAC"
BN"0"62;
%"TAP"
"1","(-6125,5400)","2","mstr_standard","I266";
;
CDS_LIB"mstr_standard"
BODY_TYPE"PLUMBING"
HDL_TAP"TRUE";
"B \NAC \NWC"9;
"S \NAC"
BN"5"73;
%"TAP"
"1","(-6125,5600)","2","mstr_standard","I267";
;
CDS_LIB"mstr_standard"
BODY_TYPE"PLUMBING"
HDL_TAP"TRUE";
"B \NAC \NWC"9;
"S \NAC"
BN"3"76;
%"TAP"
"1","(-6125,5500)","2","mstr_standard","I268";
;
CDS_LIB"mstr_standard"
BODY_TYPE"PLUMBING"
HDL_TAP"TRUE";
"B \NAC \NWC"9;
"S \NAC"
BN"4"75;
%"TAP"
"1","(-6125,5100)","2","mstr_standard","I269";
;
CDS_LIB"mstr_standard"
BODY_TYPE"PLUMBING"
HDL_TAP"TRUE";
"B \NAC \NWC"9;
"S \NAC"
BN"8"57;
%"TAP"
"1","(-6125,5200)","2","mstr_standard","I270";
;
CDS_LIB"mstr_standard"
BODY_TYPE"PLUMBING"
HDL_TAP"TRUE";
"B \NAC \NWC"9;
"S \NAC"
BN"7"69;
%"TAP"
"1","(-6125,5300)","2","mstr_standard","I271";
;
CDS_LIB"mstr_standard"
BODY_TYPE"PLUMBING"
HDL_TAP"TRUE";
"B \NAC \NWC"9;
"S \NAC"
BN"6"71;
%"TAP"
"1","(-6125,4850)","2","mstr_standard","I274";
;
CDS_LIB"mstr_standard"
BODY_TYPE"PLUMBING"
HDL_TAP"TRUE";
"B \NAC \NWC"10;
"S \NAC"
BN"0"60;
%"TAP"
"1","(-6125,5000)","2","mstr_standard","I275";
;
CDS_LIB"mstr_standard"
BODY_TYPE"PLUMBING"
HDL_TAP"TRUE";
"B \NAC \NWC"9;
"S \NAC"
BN"9"55;
%"TAP"
"1","(-6125,4650)","2","mstr_standard","I276";
;
CDS_LIB"mstr_standard"
BODY_TYPE"PLUMBING"
HDL_TAP"TRUE";
"B \NAC \NWC"10;
"S \NAC"
BN"2"58;
%"TAP"
"1","(-6125,4750)","2","mstr_standard","I277";
;
CDS_LIB"mstr_standard"
BODY_TYPE"PLUMBING"
HDL_TAP"TRUE";
"B \NAC \NWC"10;
"S \NAC"
BN"1"59;
%"TAP"
"1","(-6125,4350)","2","mstr_standard","I278";
;
CDS_LIB"mstr_standard"
BODY_TYPE"PLUMBING"
HDL_TAP"TRUE";
"B \NAC \NWC"10;
"S \NAC"
BN"5"52;
%"TAP"
"1","(-6125,4550)","2","mstr_standard","I279";
;
CDS_LIB"mstr_standard"
BODY_TYPE"PLUMBING"
HDL_TAP"TRUE";
"B \NAC \NWC"10;
"S \NAC"
BN"3"56;
%"TAP"
"1","(-6125,4450)","2","mstr_standard","I280";
;
CDS_LIB"mstr_standard"
BODY_TYPE"PLUMBING"
HDL_TAP"TRUE";
"B \NAC \NWC"10;
"S \NAC"
BN"4"54;
%"TAP"
"1","(-6125,4150)","2","mstr_standard","I281";
;
CDS_LIB"mstr_standard"
BODY_TYPE"PLUMBING"
HDL_TAP"TRUE";
"B \NAC \NWC"10;
"S \NAC"
BN"7"48;
%"TAP"
"1","(-6125,4250)","2","mstr_standard","I282";
;
CDS_LIB"mstr_standard"
BODY_TYPE"PLUMBING"
HDL_TAP"TRUE";
"B \NAC \NWC"10;
"S \NAC"
BN"6"50;
%"TAP"
"1","(-5925,4000)","2","mstr_standard","I285";
;
CDS_LIB"mstr_standard"
BODY_TYPE"PLUMBING"
HDL_TAP"TRUE";
"B \NAC \NWC"6;
"S \NAC"
BN"9"25;
%"TAP"
"1","(-6125,3950)","2","mstr_standard","I286";
;
CDS_LIB"mstr_standard"
BODY_TYPE"PLUMBING"
HDL_TAP"TRUE";
"B \NAC \NWC"10;
"S \NAC"
BN"9"27;
%"TAP"
"1","(-6125,4050)","2","mstr_standard","I287";
;
CDS_LIB"mstr_standard"
BODY_TYPE"PLUMBING"
HDL_TAP"TRUE";
"B \NAC \NWC"10;
"S \NAC"
BN"8"30;
%"TAP"
"1","(-6125,3750)","2","mstr_standard","I288";
;
CDS_LIB"mstr_standard"
BODY_TYPE"PLUMBING"
HDL_TAP"TRUE";
"B \NAC \NWC"7;
"S \NAC"
BN"1"39;
%"TAP"
"1","(-6125,3800)","2","mstr_standard","I289";
;
CDS_LIB"mstr_standard"
BODY_TYPE"PLUMBING"
HDL_TAP"TRUE";
"B \NAC \NWC"7;
"S \NAC"
BN"0"41;
%"TAP"
"1","(-6125,3700)","2","mstr_standard","I290";
;
CDS_LIB"mstr_standard"
BODY_TYPE"PLUMBING"
HDL_TAP"TRUE";
"B \NAC \NWC"7;
"S \NAC"
BN"2"37;
%"TAP"
"1","(-6125,3650)","2","mstr_standard","I291";
;
CDS_LIB"mstr_standard"
BODY_TYPE"PLUMBING"
HDL_TAP"TRUE";
"B \NAC \NWC"7;
"S \NAC"
BN"3"35;
%"TAP"
"1","(-6125,3600)","2","mstr_standard","I292";
;
CDS_LIB"mstr_standard"
BODY_TYPE"PLUMBING"
HDL_TAP"TRUE";
"B \NAC \NWC"7;
"S \NAC"
BN"4"33;
%"TAP"
"1","(-6125,3550)","2","mstr_standard","I293";
;
CDS_LIB"mstr_standard"
BODY_TYPE"PLUMBING"
HDL_TAP"TRUE";
"B \NAC \NWC"7;
"S \NAC"
BN"5"31;
%"TAP"
"1","(-6125,3500)","2","mstr_standard","I294";
;
CDS_LIB"mstr_standard"
BODY_TYPE"PLUMBING"
HDL_TAP"TRUE";
"B \NAC \NWC"7;
"S \NAC"
BN"6"28;
%"TAP"
"1","(-6125,3400)","2","mstr_standard","I295";
;
CDS_LIB"mstr_standard"
BODY_TYPE"PLUMBING"
HDL_TAP"TRUE";
"B \NAC \NWC"8;
"S \NAC"
BN"0"40;
%"TAP"
"1","(-6125,3350)","2","mstr_standard","I296";
;
CDS_LIB"mstr_standard"
BODY_TYPE"PLUMBING"
HDL_TAP"TRUE";
"B \NAC \NWC"8;
"S \NAC"
BN"1"38;
%"TAP"
"1","(-6125,3250)","2","mstr_standard","I297";
;
CDS_LIB"mstr_standard"
BODY_TYPE"PLUMBING"
HDL_TAP"TRUE";
"B \NAC \NWC"8;
"S \NAC"
BN"3"34;
%"TAP"
"1","(-6125,3300)","2","mstr_standard","I298";
;
CDS_LIB"mstr_standard"
BODY_TYPE"PLUMBING"
HDL_TAP"TRUE";
"B \NAC \NWC"8;
"S \NAC"
BN"2"36;
%"TAP"
"1","(-6125,3200)","2","mstr_standard","I299";
;
CDS_LIB"mstr_standard"
BODY_TYPE"PLUMBING"
HDL_TAP"TRUE";
"B \NAC \NWC"8;
"S \NAC"
BN"4"32;
%"TAP"
"1","(-6125,3150)","2","mstr_standard","I300";
;
CDS_LIB"mstr_standard"
BODY_TYPE"PLUMBING"
HDL_TAP"TRUE";
"B \NAC \NWC"8;
"S \NAC"
BN"5"29;
%"TAP"
"1","(-6125,3100)","2","mstr_standard","I301";
;
CDS_LIB"mstr_standard"
BODY_TYPE"PLUMBING"
HDL_TAP"TRUE";
"B \NAC \NWC"8;
"S \NAC"
BN"6"26;
%"Q_RES"
"1","(-7050,2100)","0","pure_quanta","I314";
;
LOCATION"R377"
$SEC"1"
CDS_SEC"1"
TOLERANCE"1%"
VALUE"15   "
PART_NUMBER"CS01502FB11"
PACK_TYPE"0402LF"
CDS_LIB"pure_quanta"
WATTAGE"1/16W"
MATERIAL"CHIP";
"B"
$PN"2"13;
"A"
$PN"1"11;
END.
